# S9S_MB_2U (Grand Teton) — schematic netlist excerpt (pin names and nets, part order shuffled) for the footprints in the layout excerpt that follows; sources: Cadence DE-HDL packaged netlist, KiCad conversion of 03242023_DA0F0TMBIJ0_F0T_Motherboard_J_brd_V01_OCP.brd

PC1280  Q_CAP  22UF 16V 20% X6S  pkg C0805  page 300 : A = SW_P12V_PVCCINFAON_CPU1_FLT ; B = GND
R1124  Q_RES  1K 1% CHIP  pkg 0402LF  page 158 : A = PD_SMB_OCP1_HP_ADD2 ; B = GND
C1173  Q_CAP  0.1UF 25V 10% X7R  pkg 0402  page 155 : A = P3V3_AUX ; B = GND

(kicad_pcb
	(version 20260206)
	(generator "pcbnew")
	(generator_version "10.0")
	(general
		(thickness 1.6)
		(legacy_teardrops no)
	)
	(paper "A4")
	(title_block
		(title "03242023_DA0F0TMBIJ0_F0T_Motherboard_J_brd_V01_OCP.brd")
		(comment 1 "Grand Teton / footprints 1576-1578 of 6105")
	)
	(layers
		(0 "F.Cu" signal "TOP")
		(4 "In1.Cu" signal "GND")
		(6 "In2.Cu" signal "IN1")
		(8 "In3.Cu" signal "GND1")
		(10 "In4.Cu" signal "IN2")
		(12 "In5.Cu" signal "GND2")
		(14 "In6.Cu" signal "IN3")
		(16 "In7.Cu" signal "GND3")
		(18 "In8.Cu" signal "VCC")
		(20 "In9.Cu" signal "VCC1")
		(22 "In10.Cu" signal "GND4")
		(24 "In11.Cu" signal "IN4")
		(26 "In12.Cu" signal "GND5")
		(28 "In13.Cu" signal "IN5")
		(30 "In14.Cu" signal "GND6")
		(32 "In15.Cu" signal "IN6")
		(34 "In16.Cu" signal "GND7")
		(2 "B.Cu" signal "BOTTOM")
		(9 "F.Adhes" user "F.Adhesive")
		(11 "B.Adhes" user "B.Adhesive")
		(13 "F.Paste" user "Package Geometry/Pastemask Top")
		(15 "B.Paste" user "Package Geometry/Pastemask Bottom")
		(5 "F.SilkS" user "Ref Des/Silkscreen Top")
		(7 "B.SilkS" user "Ref Des/Silkscreen Bottom")
		(1 "F.Mask" user "Board Geometry/Soldermask Top")
		(3 "B.Mask" user "Board Geometry/Soldermask Bottom")
		(17 "Dwgs.User" user "User.Drawings")
		(19 "Cmts.User" user "User.Comments")
		(21 "Eco1.User" user "User.Eco1")
		(23 "Eco2.User" user "User.Eco2")
		(25 "Edge.Cuts" user "Board Geometry/Outline")
		(27 "Margin" user)
		(31 "F.CrtYd" user "Package Geometry/Place Bound Top")
		(29 "B.CrtYd" user "Package Geometry/Place Bound Bottom")
		(35 "F.Fab" user "Ref Des/Assembly Top")
		(33 "B.Fab" user "Ref Des/Assembly Bottom")
	)
	(footprint ""
		(layer "F.Cu")
		(at 449.973954 -117.193822 180)
		(property "Reference" "R1124"
			(at 0 0 180)
			(layer "F.SilkS")
			(hide yes)
			(effects
				(font
					(size 1.27 1.27)
				)
			)
		)
		(property "Value" ""
			(at 0 0 180)
			(layer "F.Fab")
			(effects
				(font
					(size 1.27 1.27)
				)
			)
		)
		(duplicate_pad_numbers_are_jumpers no)
		(fp_line
			(start 0.7874 0.4064)
			(end -0.7874 0.4064)
			(stroke
				(width 0.1524)
				(type default)
			)
			(layer "F.SilkS")
		)
		(fp_line
			(start 0.7874 -0.4064)
			(end 0.7874 0.4064)
			(stroke
				(width 0.1524)
				(type default)
			)
			(layer "F.SilkS")
		)
		(fp_line
			(start -0.7874 0.4064)
			(end -0.7874 -0.4064)
			(stroke
				(width 0.1524)
				(type default)
			)
			(layer "F.SilkS")
		)
		(fp_line
			(start -0.7874 -0.4064)
			(end 0.7874 -0.4064)
			(stroke
				(width 0.1524)
				(type default)
			)
			(layer "F.SilkS")
		)
		(fp_line
			(start 0.67945 0.3048)
			(end 0.120396 0.3048)
			(stroke
				(width 0.1)
				(type default)
			)
			(layer "F.Fab")
		)
		(fp_line
			(start 0.67945 -0.3048)
			(end 0.67945 0.3048)
			(stroke
				(width 0.1)
				(type default)
			)
			(layer "F.Fab")
		)
		(fp_line
			(start 0.12065 -0.2794)
			(end 0.12065 -0.3048)
			(stroke
				(width 0.1)
				(type default)
			)
			(layer "F.Fab")
		)
		(fp_line
			(start 0.12065 -0.3048)
			(end 0.67945 -0.3048)
			(stroke
				(width 0.1)
				(type default)
			)
			(layer "F.Fab")
		)
		(fp_line
			(start 0.120396 0.3048)
			(end 0.120396 0.2794)
			(stroke
				(width 0.1)
				(type default)
			)
			(layer "F.Fab")
		)
		(fp_line
			(start 0.120396 0.2794)
			(end -0.12065 0.2794)
			(stroke
				(width 0.1)
				(type default)
			)
			(layer "F.Fab")
		)
		(fp_line
			(start -0.12065 0.3048)
			(end -0.67945 0.3048)
			(stroke
				(width 0.1)
				(type default)
			)
			(layer "F.Fab")
		)
		(fp_line
			(start -0.12065 0.2794)
			(end -0.12065 0.3048)
			(stroke
				(width 0.1)
				(type default)
			)
			(layer "F.Fab")
		)
		(fp_line
			(start -0.12065 -0.2794)
			(end 0.12065 -0.2794)
			(stroke
				(width 0.1)
				(type default)
			)
			(layer "F.Fab")
		)
		(fp_line
			(start -0.12065 -0.305054)
			(end -0.12065 -0.2794)
			(stroke
				(width 0.1)
				(type default)
			)
			(layer "F.Fab")
		)
		(fp_line
			(start -0.67945 0.3048)
			(end -0.67945 -0.305054)
			(stroke
				(width 0.1)
				(type default)
			)
			(layer "F.Fab")
		)
		(fp_line
			(start -0.67945 -0.305054)
			(end -0.12065 -0.305054)
			(stroke
				(width 0.1)
				(type default)
			)
			(layer "F.Fab")
		)
		(pad "1" smd circle
			(at -0.40005 0 180)
			(size 0 0)
			(layers "F.Cu" "F.Mask" "F.Paste")
			(net "PD_SMB_OCP1_HP_ADD2")
		)
		(pad "2" smd circle
			(at 0.40005 0 180)
			(size 0 0)
			(layers "F.Cu" "F.Mask" "F.Paste")
			(net "GND")
		)
	)
	(footprint ""
		(layer "F.Cu")
		(at 458.41666 -39.765478)
		(property "Reference" "C1173"
			(at 0 0 0)
			(layer "F.SilkS")
			(hide yes)
			(effects
				(font
					(size 1.27 1.27)
				)
			)
		)
		(property "Value" ""
			(at 0 0 0)
			(layer "F.Fab")
			(effects
				(font
					(size 1.27 1.27)
				)
			)
		)
		(duplicate_pad_numbers_are_jumpers no)
		(fp_line
			(start -0.7874 -0.4064)
			(end 0.7874 -0.4064)
			(stroke
				(width 0.1524)
				(type default)
			)
			(layer "F.SilkS")
		)
		(fp_line
			(start -0.7874 0.4064)
			(end -0.7874 -0.4064)
			(stroke
				(width 0.1524)
				(type default)
			)
			(layer "F.SilkS")
		)
		(fp_line
			(start 0.7874 -0.4064)
			(end 0.7874 0.4064)
			(stroke
				(width 0.1524)
				(type default)
			)
			(layer "F.SilkS")
		)
		(fp_line
			(start 0.7874 0.4064)
			(end -0.7874 0.4064)
			(stroke
				(width 0.1524)
				(type default)
			)
			(layer "F.SilkS")
		)
		(fp_line
			(start -0.67945 -0.305054)
			(end -0.12065 -0.305054)
			(stroke
				(width 0.1)
				(type default)
			)
			(layer "F.Fab")
		)
		(fp_line
			(start -0.67945 0.3048)
			(end -0.67945 -0.305054)
			(stroke
				(width 0.1)
				(type default)
			)
			(layer "F.Fab")
		)
		(fp_line
			(start -0.12065 -0.305054)
			(end -0.12065 -0.2794)
			(stroke
				(width 0.1)
				(type default)
			)
			(layer "F.Fab")
		)
		(fp_line
			(start -0.12065 -0.2794)
			(end 0.12065 -0.2794)
			(stroke
				(width 0.1)
				(type default)
			)
			(layer "F.Fab")
		)
		(fp_line
			(start -0.12065 0.2794)
			(end -0.12065 0.3048)
			(stroke
				(width 0.1)
				(type default)
			)
			(layer "F.Fab")
		)
		(fp_line
			(start -0.12065 0.3048)
			(end -0.67945 0.3048)
			(stroke
				(width 0.1)
				(type default)
			)
			(layer "F.Fab")
		)
		(fp_line
			(start 0.120396 0.2794)
			(end -0.12065 0.2794)
			(stroke
				(width 0.1)
				(type default)
			)
			(layer "F.Fab")
		)
		(fp_line
			(start 0.120396 0.3048)
			(end 0.120396 0.2794)
			(stroke
				(width 0.1)
				(type default)
			)
			(layer "F.Fab")
		)
		(fp_line
			(start 0.12065 -0.3048)
			(end 0.67945 -0.3048)
			(stroke
				(width 0.1)
				(type default)
			)
			(layer "F.Fab")
		)
		(fp_line
			(start 0.12065 -0.2794)
			(end 0.12065 -0.3048)
			(stroke
				(width 0.1)
				(type default)
			)
			(layer "F.Fab")
		)
		(fp_line
			(start 0.67945 -0.3048)
			(end 0.67945 0.3048)
			(stroke
				(width 0.1)
				(type default)
			)
			(layer "F.Fab")
		)
		(fp_line
			(start 0.67945 0.3048)
			(end 0.120396 0.3048)
			(stroke
				(width 0.1)
				(type default)
			)
			(layer "F.Fab")
		)
		(pad "1" smd circle
			(at -0.40005 0)
			(size 0 0)
			(layers "F.Cu" "F.Mask" "F.Paste")
			(net "P3V3_AUX")
		)
		(pad "2" smd circle
			(at 0.40005 0)
			(size 0 0)
			(layers "F.Cu" "F.Mask" "F.Paste")
			(net "GND")
		)
	)
	(footprint ""
		(layer "F.Cu")
		(at 17.36471 -180.522626 90)
		(property "Reference" "PC1280"
			(at 0 0 90)
			(layer "F.SilkS")
			(hide yes)
			(effects
				(font
					(size 1.27 1.27)
				)
			)
		)
		(property "Value" ""
			(at 0 0 90)
			(layer "F.Fab")
			(effects
				(font
					(size 1.27 1.27)
				)
			)
		)
		(duplicate_pad_numbers_are_jumpers no)
		(fp_line
			(start 1.524 -0.762)
			(end 1.524 0.762)
			(stroke
				(width 0.1524)
				(type default)
			)
			(layer "F.SilkS")
		)
		(fp_line
			(start -1.524 -0.762)
			(end 1.524 -0.762)
			(stroke
				(width 0.1524)
				(type default)
			)
			(layer "F.SilkS")
		)
		(fp_line
			(start 1.524 0.762)
			(end -1.524 0.762)
			(stroke
				(width 0.1524)
				(type default)
			)
			(layer "F.SilkS")
		)
		(fp_line
			(start -1.524 0.762)
			(end -1.524 -0.762)
			(stroke
				(width 0.1524)
				(type default)
			)
			(layer "F.SilkS")
		)
		(fp_line
			(start 1.1049 -0.724916)
			(end -1.1049 -0.724916)
			(stroke
				(width 0.1)
				(type default)
			)
			(layer "F.Fab")
		)
		(fp_line
			(start -1.1049 -0.724916)
			(end -1.1049 0.724916)
			(stroke
				(width 0.1)
				(type default)
			)
			(layer "F.Fab")
		)
		(fp_line
			(start 1.1049 0.724916)
			(end 1.1049 -0.724916)
			(stroke
				(width 0.1)
				(type default)
			)
			(layer "F.Fab")
		)
		(fp_line
			(start -1.1049 0.724916)
			(end 1.1049 0.724916)
			(stroke
				(width 0.1)
				(type default)
			)
			(layer "F.Fab")
		)
		(pad "1" smd rect
			(at -0.889 0 270)
			(size 1.016 1.27)
			(layers "F.Cu" "F.Mask" "F.Paste")
			(net "SW_P12V_PVCCINFAON_CPU1_FLT")
		)
		(pad "2" smd rect
			(at 0.889 0 270)
			(size 1.016 1.27)
			(layers "F.Cu" "F.Mask" "F.Paste")
			(net "GND")
		)
	)
)
